(kicad_pcb
	(version 20260206)
	(generator "pcbnew")
	(generator_version "10.0")
	(general
		(thickness 1.6)
		(legacy_teardrops no)
	)
	(paper "A4")
	(title_block
		(title "01162023_DA0F0TEBIF0_F0T_Expander_BD_F_brd_V02_OCP.brd")
		(comment 1 "Grand Teton / footprints 321-327 of 9728")
	)
	(layers
		(0 "F.Cu" signal "TOP")
		(4 "In1.Cu" signal "GND")
		(6 "In2.Cu" signal "VCC")
		(8 "In3.Cu" signal "VCC1")
		(10 "In4.Cu" signal "GND1")
		(12 "In5.Cu" signal "IN1")
		(14 "In6.Cu" signal "GND2")
		(16 "In7.Cu" signal "IN2")
		(18 "In8.Cu" signal "GND3")
		(20 "In9.Cu" signal "IN3")
		(22 "In10.Cu" signal "GND4")
		(24 "In11.Cu" signal "IN4")
		(26 "In12.Cu" signal "GND5")
		(28 "In13.Cu" signal "IN5")
		(30 "In14.Cu" signal "GND6")
		(32 "In15.Cu" signal "IN6")
		(34 "In16.Cu" signal "GND7")
		(2 "B.Cu" signal "BOTTOM")
		(9 "F.Adhes" user "F.Adhesive")
		(11 "B.Adhes" user "B.Adhesive")
		(13 "F.Paste" user "Package Geometry/Pastemask Top")
		(15 "B.Paste" user "Package Geometry/Pastemask Bottom")
		(5 "F.SilkS" user "Ref Des/Silkscreen Top")
		(7 "B.SilkS" user "Ref Des/Silkscreen Bottom")
		(1 "F.Mask" user "Board Geometry/Soldermask Top")
		(3 "B.Mask" user "Board Geometry/Soldermask Bottom")
		(17 "Dwgs.User" user "User.Drawings")
		(19 "Cmts.User" user "User.Comments")
		(21 "Eco1.User" user "User.Eco1")
		(23 "Eco2.User" user "User.Eco2")
		(25 "Edge.Cuts" user "Board Geometry/Outline")
		(27 "Margin" user)
		(31 "F.CrtYd" user "Package Geometry/Place Bound Top")
		(29 "B.CrtYd" user "Package Geometry/Place Bound Bottom")
		(35 "F.Fab" user "Ref Des/Assembly Top")
		(33 "B.Fab" user "Ref Des/Assembly Bottom")
	)
	(footprint ""
		(layer "F.Cu")
		(at 231.844596 -277.535386)
		(property "Reference" "R783"
			(at 0 0 0)
			(layer "F.SilkS")
			(hide yes)
			(effects
				(font
					(size 1.27 1.27)
				)
			)
		)
		(property "Value" ""
			(at 0 0 0)
			(layer "F.Fab")
			(effects
				(font
					(size 1.27 1.27)
				)
			)
		)
		(duplicate_pad_numbers_are_jumpers no)
		(fp_line
			(start -0.7874 -0.4064)
			(end 0.7874 -0.4064)
			(stroke
				(width 0.1524)
				(type default)
			)
			(layer "F.SilkS")
		)
		(fp_line
			(start -0.7874 0.4064)
			(end -0.7874 -0.4064)
			(stroke
				(width 0.1524)
				(type default)
			)
			(layer "F.SilkS")
		)
		(fp_line
			(start 0.7874 -0.4064)
			(end 0.7874 0.4064)
			(stroke
				(width 0.1524)
				(type default)
			)
			(layer "F.SilkS")
		)
		(fp_line
			(start 0.7874 0.4064)
			(end -0.7874 0.4064)
			(stroke
				(width 0.1524)
				(type default)
			)
			(layer "F.SilkS")
		)
		(fp_line
			(start -0.67945 -0.305054)
			(end -0.12065 -0.305054)
			(stroke
				(width 0.1)
				(type default)
			)
			(layer "F.Fab")
		)
		(fp_line
			(start -0.67945 0.3048)
			(end -0.67945 -0.305054)
			(stroke
				(width 0.1)
				(type default)
			)
			(layer "F.Fab")
		)
		(fp_line
			(start -0.12065 -0.305054)
			(end -0.12065 -0.2794)
			(stroke
				(width 0.1)
				(type default)
			)
			(layer "F.Fab")
		)
		(fp_line
			(start -0.12065 -0.2794)
			(end 0.12065 -0.2794)
			(stroke
				(width 0.1)
				(type default)
			)
			(layer "F.Fab")
		)
		(fp_line
			(start -0.12065 0.2794)
			(end -0.12065 0.3048)
			(stroke
				(width 0.1)
				(type default)
			)
			(layer "F.Fab")
		)
		(fp_line
			(start -0.12065 0.3048)
			(end -0.67945 0.3048)
			(stroke
				(width 0.1)
				(type default)
			)
			(layer "F.Fab")
		)
		(fp_line
			(start 0.120396 0.2794)
			(end -0.12065 0.2794)
			(stroke
				(width 0.1)
				(type default)
			)
			(layer "F.Fab")
		)
		(fp_line
			(start 0.120396 0.3048)
			(end 0.120396 0.2794)
			(stroke
				(width 0.1)
				(type default)
			)
			(layer "F.Fab")
		)
		(fp_line
			(start 0.12065 -0.3048)
			(end 0.67945 -0.3048)
			(stroke
				(width 0.1)
				(type default)
			)
			(layer "F.Fab")
		)
		(fp_line
			(start 0.12065 -0.2794)
			(end 0.12065 -0.3048)
			(stroke
				(width 0.1)
				(type default)
			)
			(layer "F.Fab")
		)
		(fp_line
			(start 0.67945 -0.3048)
			(end 0.67945 0.3048)
			(stroke
				(width 0.1)
				(type default)
			)
			(layer "F.Fab")
		)
		(fp_line
			(start 0.67945 0.3048)
			(end 0.120396 0.3048)
			(stroke
				(width 0.1)
				(type default)
			)
			(layer "F.Fab")
		)
		(pad "1" smd circle
			(at -0.40005 0)
			(size 0 0)
			(layers "F.Cu" "F.Mask" "F.Paste")
			(net "PEX1_P1V25_ADC_ALERT_N")
		)
		(pad "2" smd circle
			(at 0.40005 0)
			(size 0 0)
			(layers "F.Cu" "F.Mask" "F.Paste")
			(net "PEX_ADC_ALERT_N")
		)
	)
	(footprint ""
		(layer "F.Cu")
		(at 407.696162 -390.990836)
		(property "Reference" "R1853"
			(at 0 0 0)
			(layer "F.SilkS")
			(hide yes)
			(effects
				(font
					(size 1.27 1.27)
				)
			)
		)
		(property "Value" ""
			(at 0 0 0)
			(layer "F.Fab")
			(effects
				(font
					(size 1.27 1.27)
				)
			)
		)
		(duplicate_pad_numbers_are_jumpers no)
		(fp_line
			(start -0.7874 -0.4064)
			(end 0.7874 -0.4064)
			(stroke
				(width 0.1524)
				(type default)
			)
			(layer "F.SilkS")
		)
		(fp_line
			(start -0.7874 0.4064)
			(end -0.7874 -0.4064)
			(stroke
				(width 0.1524)
				(type default)
			)
			(layer "F.SilkS")
		)
		(fp_line
			(start 0.7874 -0.4064)
			(end 0.7874 0.4064)
			(stroke
				(width 0.1524)
				(type default)
			)
			(layer "F.SilkS")
		)
		(fp_line
			(start 0.7874 0.4064)
			(end -0.7874 0.4064)
			(stroke
				(width 0.1524)
				(type default)
			)
			(layer "F.SilkS")
		)
		(fp_line
			(start -0.67945 -0.305054)
			(end -0.12065 -0.305054)
			(stroke
				(width 0.1)
				(type default)
			)
			(layer "F.Fab")
		)
		(fp_line
			(start -0.67945 0.3048)
			(end -0.67945 -0.305054)
			(stroke
				(width 0.1)
				(type default)
			)
			(layer "F.Fab")
		)
		(fp_line
			(start -0.12065 -0.305054)
			(end -0.12065 -0.2794)
			(stroke
				(width 0.1)
				(type default)
			)
			(layer "F.Fab")
		)
		(fp_line
			(start -0.12065 -0.2794)
			(end 0.12065 -0.2794)
			(stroke
				(width 0.1)
				(type default)
			)
			(layer "F.Fab")
		)
		(fp_line
			(start -0.12065 0.2794)
			(end -0.12065 0.3048)
			(stroke
				(width 0.1)
				(type default)
			)
			(layer "F.Fab")
		)
		(fp_line
			(start -0.12065 0.3048)
			(end -0.67945 0.3048)
			(stroke
				(width 0.1)
				(type default)
			)
			(layer "F.Fab")
		)
		(fp_line
			(start 0.120396 0.2794)
			(end -0.12065 0.2794)
			(stroke
				(width 0.1)
				(type default)
			)
			(layer "F.Fab")
		)
		(fp_line
			(start 0.120396 0.3048)
			(end 0.120396 0.2794)
			(stroke
				(width 0.1)
				(type default)
			)
			(layer "F.Fab")
		)
		(fp_line
			(start 0.12065 -0.3048)
			(end 0.67945 -0.3048)
			(stroke
				(width 0.1)
				(type default)
			)
			(layer "F.Fab")
		)
		(fp_line
			(start 0.12065 -0.2794)
			(end 0.12065 -0.3048)
			(stroke
				(width 0.1)
				(type default)
			)
			(layer "F.Fab")
		)
		(fp_line
			(start 0.67945 -0.3048)
			(end 0.67945 0.3048)
			(stroke
				(width 0.1)
				(type default)
			)
			(layer "F.Fab")
		)
		(fp_line
			(start 0.67945 0.3048)
			(end 0.120396 0.3048)
			(stroke
				(width 0.1)
				(type default)
			)
			(layer "F.Fab")
		)
		(pad "1" smd circle
			(at -0.40005 0)
			(size 0 0)
			(layers "F.Cu" "F.Mask" "F.Paste")
			(net "GPU_BB_RSVD_1_R")
		)
		(pad "2" smd circle
			(at 0.40005 0)
			(size 0 0)
			(layers "F.Cu" "F.Mask" "F.Paste")
			(net "GPU_BB_RSVD_1")
		)
	)
	(footprint ""
		(layer "F.Cu")
		(at 203.849732 -300.60265 90)
		(property "Reference" "R6392"
			(at 0 0 90)
			(layer "F.SilkS")
			(hide yes)
			(effects
				(font
					(size 1.27 1.27)
				)
			)
		)
		(property "Value" ""
			(at 0 0 90)
			(layer "F.Fab")
			(effects
				(font
					(size 1.27 1.27)
				)
			)
		)
		(duplicate_pad_numbers_are_jumpers no)
		(fp_line
			(start 0.7874 -0.4064)
			(end 0.7874 0.4064)
			(stroke
				(width 0.1524)
				(type default)
			)
			(layer "F.SilkS")
		)
		(fp_line
			(start -0.7874 -0.4064)
			(end 0.7874 -0.4064)
			(stroke
				(width 0.1524)
				(type default)
			)
			(layer "F.SilkS")
		)
		(fp_line
			(start 0.7874 0.4064)
			(end -0.7874 0.4064)
			(stroke
				(width 0.1524)
				(type default)
			)
			(layer "F.SilkS")
		)
		(fp_line
			(start -0.7874 0.4064)
			(end -0.7874 -0.4064)
			(stroke
				(width 0.1524)
				(type default)
			)
			(layer "F.SilkS")
		)
		(fp_line
			(start -0.12065 -0.305054)
			(end -0.12065 -0.2794)
			(stroke
				(width 0.1)
				(type default)
			)
			(layer "F.Fab")
		)
		(fp_line
			(start -0.67945 -0.305054)
			(end -0.12065 -0.305054)
			(stroke
				(width 0.1)
				(type default)
			)
			(layer "F.Fab")
		)
		(fp_line
			(start 0.67945 -0.3048)
			(end 0.67945 0.3048)
			(stroke
				(width 0.1)
				(type default)
			)
			(layer "F.Fab")
		)
		(fp_line
			(start 0.12065 -0.3048)
			(end 0.67945 -0.3048)
			(stroke
				(width 0.1)
				(type default)
			)
			(layer "F.Fab")
		)
		(fp_line
			(start 0.12065 -0.2794)
			(end 0.12065 -0.3048)
			(stroke
				(width 0.1)
				(type default)
			)
			(layer "F.Fab")
		)
		(fp_line
			(start -0.12065 -0.2794)
			(end 0.12065 -0.2794)
			(stroke
				(width 0.1)
				(type default)
			)
			(layer "F.Fab")
		)
		(fp_line
			(start 0.120396 0.2794)
			(end -0.12065 0.2794)
			(stroke
				(width 0.1)
				(type default)
			)
			(layer "F.Fab")
		)
		(fp_line
			(start -0.12065 0.2794)
			(end -0.12065 0.3048)
			(stroke
				(width 0.1)
				(type default)
			)
			(layer "F.Fab")
		)
		(fp_line
			(start 0.67945 0.3048)
			(end 0.120396 0.3048)
			(stroke
				(width 0.1)
				(type default)
			)
			(layer "F.Fab")
		)
		(fp_line
			(start 0.120396 0.3048)
			(end 0.120396 0.2794)
			(stroke
				(width 0.1)
				(type default)
			)
			(layer "F.Fab")
		)
		(fp_line
			(start -0.12065 0.3048)
			(end -0.67945 0.3048)
			(stroke
				(width 0.1)
				(type default)
			)
			(layer "F.Fab")
		)
		(fp_line
			(start -0.67945 0.3048)
			(end -0.67945 -0.305054)
			(stroke
				(width 0.1)
				(type default)
			)
			(layer "F.Fab")
		)
		(pad "1" smd circle
			(at -0.40005 0 90)
			(size 0 0)
			(layers "F.Cu" "F.Mask" "F.Paste")
			(net "RST_PEX1_S1_PERST_N")
		)
		(pad "2" smd circle
			(at 0.40005 0 90)
			(size 0 0)
			(layers "F.Cu" "F.Mask" "F.Paste")
			(net "RST_PEX1_S1_PERST_R_N")
		)
	)
	(footprint ""
		(layer "F.Cu")
		(at 392.467338 -246.313198 180)
		(property "Reference" "R6614"
			(at 0 0 180)
			(layer "F.SilkS")
			(hide yes)
			(effects
				(font
					(size 1.27 1.27)
				)
			)
		)
		(property "Value" ""
			(at 0 0 180)
			(layer "F.Fab")
			(effects
				(font
					(size 1.27 1.27)
				)
			)
		)
		(duplicate_pad_numbers_are_jumpers no)
		(fp_line
			(start 0.7874 0.4064)
			(end -0.7874 0.4064)
			(stroke
				(width 0.1524)
				(type default)
			)
			(layer "F.SilkS")
		)
		(fp_line
			(start 0.7874 -0.4064)
			(end 0.7874 0.4064)
			(stroke
				(width 0.1524)
				(type default)
			)
			(layer "F.SilkS")
		)
		(fp_line
			(start -0.7874 0.4064)
			(end -0.7874 -0.4064)
			(stroke
				(width 0.1524)
				(type default)
			)
			(layer "F.SilkS")
		)
		(fp_line
			(start -0.7874 -0.4064)
			(end 0.7874 -0.4064)
			(stroke
				(width 0.1524)
				(type default)
			)
			(layer "F.SilkS")
		)
		(fp_line
			(start 0.67945 0.3048)
			(end 0.120396 0.3048)
			(stroke
				(width 0.1)
				(type default)
			)
			(layer "F.Fab")
		)
		(fp_line
			(start 0.67945 -0.3048)
			(end 0.67945 0.3048)
			(stroke
				(width 0.1)
				(type default)
			)
			(layer "F.Fab")
		)
		(fp_line
			(start 0.12065 -0.2794)
			(end 0.12065 -0.3048)
			(stroke
				(width 0.1)
				(type default)
			)
			(layer "F.Fab")
		)
		(fp_line
			(start 0.12065 -0.3048)
			(end 0.67945 -0.3048)
			(stroke
				(width 0.1)
				(type default)
			)
			(layer "F.Fab")
		)
		(fp_line
			(start 0.120396 0.3048)
			(end 0.120396 0.2794)
			(stroke
				(width 0.1)
				(type default)
			)
			(layer "F.Fab")
		)
		(fp_line
			(start 0.120396 0.2794)
			(end -0.12065 0.2794)
			(stroke
				(width 0.1)
				(type default)
			)
			(layer "F.Fab")
		)
		(fp_line
			(start -0.12065 0.3048)
			(end -0.67945 0.3048)
			(stroke
				(width 0.1)
				(type default)
			)
			(layer "F.Fab")
		)
		(fp_line
			(start -0.12065 0.2794)
			(end -0.12065 0.3048)
			(stroke
				(width 0.1)
				(type default)
			)
			(layer "F.Fab")
		)
		(fp_line
			(start -0.12065 -0.2794)
			(end 0.12065 -0.2794)
			(stroke
				(width 0.1)
				(type default)
			)
			(layer "F.Fab")
		)
		(fp_line
			(start -0.12065 -0.305054)
			(end -0.12065 -0.2794)
			(stroke
				(width 0.1)
				(type default)
			)
			(layer "F.Fab")
		)
		(fp_line
			(start -0.67945 0.3048)
			(end -0.67945 -0.305054)
			(stroke
				(width 0.1)
				(type default)
			)
			(layer "F.Fab")
		)
		(fp_line
			(start -0.67945 -0.305054)
			(end -0.12065 -0.305054)
			(stroke
				(width 0.1)
				(type default)
			)
			(layer "F.Fab")
		)
		(pad "1" smd circle
			(at -0.40005 0 180)
			(size 0 0)
			(layers "F.Cu" "F.Mask" "F.Paste")
			(net "UART_PEX1_SDB_BUF_R_TX")
		)
		(pad "2" smd circle
			(at 0.40005 0 180)
			(size 0 0)
			(layers "F.Cu" "F.Mask" "F.Paste")
			(net "UART_PEX1_SDB_BUF_R1_TX")
		)
	)
	(footprint ""
		(layer "F.Cu")
		(at 228.783134 -254.18542 -90)
		(property "Reference" "C4299"
			(at 0 0 270)
			(layer "F.SilkS")
			(hide yes)
			(effects
				(font
					(size 1.27 1.27)
				)
			)
		)
		(property "Value" ""
			(at 0 0 270)
			(layer "F.Fab")
			(effects
				(font
					(size 1.27 1.27)
				)
			)
		)
		(duplicate_pad_numbers_are_jumpers no)
		(fp_line
			(start -1.2954 0.5842)
			(end -1.2954 -0.5842)
			(stroke
				(width 0.1524)
				(type default)
			)
			(layer "F.SilkS")
		)
		(fp_line
			(start 1.2954 0.5842)
			(end -1.2954 0.5842)
			(stroke
				(width 0.1524)
				(type default)
			)
			(layer "F.SilkS")
		)
		(fp_line
			(start -1.2954 -0.5842)
			(end 1.2954 -0.5842)
			(stroke
				(width 0.1524)
				(type default)
			)
			(layer "F.SilkS")
		)
		(fp_line
			(start 1.2954 -0.5842)
			(end 1.2954 0.5842)
			(stroke
				(width 0.1524)
				(type default)
			)
			(layer "F.SilkS")
		)
		(fp_line
			(start -0.8636 0.4572)
			(end -0.8636 0.4064)
			(stroke
				(width 0.1)
				(type default)
			)
			(layer "F.Fab")
		)
		(fp_line
			(start 0.8636 0.4572)
			(end -0.8636 0.4572)
			(stroke
				(width 0.1)
				(type default)
			)
			(layer "F.Fab")
		)
		(fp_line
			(start -1.1938 0.4064)
			(end -1.1938 -0.4064)
			(stroke
				(width 0.1)
				(type default)
			)
			(layer "F.Fab")
		)
		(fp_line
			(start -0.8636 0.4064)
			(end -1.1938 0.4064)
			(stroke
				(width 0.1)
				(type default)
			)
			(layer "F.Fab")
		)
		(fp_line
			(start 0.8636 0.4064)
			(end 0.8636 0.4572)
			(stroke
				(width 0.1)
				(type default)
			)
			(layer "F.Fab")
		)
		(fp_line
			(start 1.1938 0.4064)
			(end 0.8636 0.4064)
			(stroke
				(width 0.1)
				(type default)
			)
			(layer "F.Fab")
		)
		(fp_line
			(start -1.1938 -0.4064)
			(end -0.8636 -0.4064)
			(stroke
				(width 0.1)
				(type default)
			)
			(layer "F.Fab")
		)
		(fp_line
			(start -0.8636 -0.4064)
			(end -0.8636 -0.4572)
			(stroke
				(width 0.1)
				(type default)
			)
			(layer "F.Fab")
		)
		(fp_line
			(start 0.8636 -0.4064)
			(end 1.1938 -0.4064)
			(stroke
				(width 0.1)
				(type default)
			)
			(layer "F.Fab")
		)
		(fp_line
			(start 1.1938 -0.4064)
			(end 1.1938 0.4064)
			(stroke
				(width 0.1)
				(type default)
			)
			(layer "F.Fab")
		)
		(fp_line
			(start -0.8636 -0.4572)
			(end 0.8636 -0.4572)
			(stroke
				(width 0.1)
				(type default)
			)
			(layer "F.Fab")
		)
		(fp_line
			(start 0.8636 -0.4572)
			(end 0.8636 -0.4064)
			(stroke
				(width 0.1)
				(type default)
			)
			(layer "F.Fab")
		)
		(pad "1" smd rect
			(at -0.7366 0 180)
			(size 0.7112 0.8128)
			(layers "F.Cu" "F.Mask" "F.Paste")
			(net "P1V25_SERDES_VDDPLL_PEX1_C9")
		)
		(pad "2" smd rect
			(at 0.7366 0 180)
			(size 0.7112 0.8128)
			(layers "F.Cu" "F.Mask" "F.Paste")
			(net "GND")
		)
	)
	(footprint ""
		(layer "F.Cu")
		(at 211.892388 -28.225242 180)
		(property "Reference" "C307"
			(at 0 0 180)
			(layer "F.SilkS")
			(hide yes)
			(effects
				(font
					(size 1.27 1.27)
				)
			)
		)
		(property "Value" ""
			(at 0 0 180)
			(layer "F.Fab")
			(effects
				(font
					(size 1.27 1.27)
				)
			)
		)
		(duplicate_pad_numbers_are_jumpers no)
		(fp_line
			(start 0.299974 0.150114)
			(end -0.299974 0.150114)
			(stroke
				(width 0.1)
				(type default)
			)
			(layer "F.Fab")
		)
		(fp_line
			(start 0.299974 -0.150114)
			(end 0.299974 0.150114)
			(stroke
				(width 0.1)
				(type default)
			)
			(layer "F.Fab")
		)
		(fp_line
			(start -0.299974 0.150114)
			(end -0.299974 -0.150114)
			(stroke
				(width 0.1)
				(type default)
			)
			(layer "F.Fab")
		)
		(fp_line
			(start -0.299974 -0.150114)
			(end 0.299974 -0.150114)
			(stroke
				(width 0.1)
				(type default)
			)
			(layer "F.Fab")
		)
		(pad "1" smd rect
			(at -0.2667 0 180)
			(size 0.3048 0.381)
			(layers "F.Cu" "F.Mask" "F.Paste")
			(net "P5E_PEX1_STN2_TX_DN<32>")
		)
		(pad "2" smd rect
			(at 0.2667 0 180)
			(size 0.3048 0.381)
			(layers "F.Cu" "F.Mask" "F.Paste")
			(net "P5E_PEX1_STN2_TX_C_DN<32>")
		)
	)
	(footprint ""
		(layer "F.Cu")
		(at 217.235786 -218.302586 180)
		(property "Reference" "R1500"
			(at 0 0 180)
			(layer "F.SilkS")
			(hide yes)
			(effects
				(font
					(size 1.27 1.27)
				)
			)
		)
		(property "Value" ""
			(at 0 0 180)
			(layer "F.Fab")
			(effects
				(font
					(size 1.27 1.27)
				)
			)
		)
		(duplicate_pad_numbers_are_jumpers no)
		(fp_line
			(start 0.7874 0.4064)
			(end -0.7874 0.4064)
			(stroke
				(width 0.1524)
				(type default)
			)
			(layer "F.SilkS")
		)
		(fp_line
			(start 0.7874 -0.4064)
			(end 0.7874 0.4064)
			(stroke
				(width 0.1524)
				(type default)
			)
			(layer "F.SilkS")
		)
		(fp_line
			(start -0.7874 0.4064)
			(end -0.7874 -0.4064)
			(stroke
				(width 0.1524)
				(type default)
			)
			(layer "F.SilkS")
		)
		(fp_line
			(start -0.7874 -0.4064)
			(end 0.7874 -0.4064)
			(stroke
				(width 0.1524)
				(type default)
			)
			(layer "F.SilkS")
		)
		(fp_line
			(start 0.67945 0.3048)
			(end 0.120396 0.3048)
			(stroke
				(width 0.1)
				(type default)
			)
			(layer "F.Fab")
		)
		(fp_line
			(start 0.67945 -0.3048)
			(end 0.67945 0.3048)
			(stroke
				(width 0.1)
				(type default)
			)
			(layer "F.Fab")
		)
		(fp_line
			(start 0.12065 -0.2794)
			(end 0.12065 -0.3048)
			(stroke
				(width 0.1)
				(type default)
			)
			(layer "F.Fab")
		)
		(fp_line
			(start 0.12065 -0.3048)
			(end 0.67945 -0.3048)
			(stroke
				(width 0.1)
				(type default)
			)
			(layer "F.Fab")
		)
		(fp_line
			(start 0.120396 0.3048)
			(end 0.120396 0.2794)
			(stroke
				(width 0.1)
				(type default)
			)
			(layer "F.Fab")
		)
		(fp_line
			(start 0.120396 0.2794)
			(end -0.12065 0.2794)
			(stroke
				(width 0.1)
				(type default)
			)
			(layer "F.Fab")
		)
		(fp_line
			(start -0.12065 0.3048)
			(end -0.67945 0.3048)
			(stroke
				(width 0.1)
				(type default)
			)
			(layer "F.Fab")
		)
		(fp_line
			(start -0.12065 0.2794)
			(end -0.12065 0.3048)
			(stroke
				(width 0.1)
				(type default)
			)
			(layer "F.Fab")
		)
		(fp_line
			(start -0.12065 -0.2794)
			(end 0.12065 -0.2794)
			(stroke
				(width 0.1)
				(type default)
			)
			(layer "F.Fab")
		)
		(fp_line
			(start -0.12065 -0.305054)
			(end -0.12065 -0.2794)
			(stroke
				(width 0.1)
				(type default)
			)
			(layer "F.Fab")
		)
		(fp_line
			(start -0.67945 0.3048)
			(end -0.67945 -0.305054)
			(stroke
				(width 0.1)
				(type default)
			)
			(layer "F.Fab")
		)
		(fp_line
			(start -0.67945 -0.305054)
			(end -0.12065 -0.305054)
			(stroke
				(width 0.1)
				(type default)
			)
			(layer "F.Fab")
		)
		(pad "1" smd circle
			(at -0.40005 0 180)
			(size 0 0)
			(layers "F.Cu" "F.Mask" "F.Paste")
			(net "SMB_NIC5_SCL")
		)
		(pad "2" smd circle
			(at 0.40005 0 180)
			(size 0 0)
			(layers "F.Cu" "F.Mask" "F.Paste")
			(net "SMB_NIC5_R_SCL")
		)
	)
)
